(kicad_pcb
	(version 20260206)
	(generator "pcbnew")
	(generator_version "10.0")
	(general
		(thickness 1.6)
		(legacy_teardrops no)
	)
	(paper "A4")
	(title_block
		(title "Wiwynn_Tioga_Pass_MB.brd")
		(comment 1 "Tioga Pass / footprints 2514-2521 of 4770")
	)
	(layers
		(0 "F.Cu" signal "TOP")
		(4 "In1.Cu" signal "L2GND")
		(6 "In2.Cu" signal "L3")
		(8 "In3.Cu" signal "L4GND")
		(10 "In4.Cu" signal "L5")
		(12 "In5.Cu" signal "L6GND")
		(14 "In6.Cu" signal "L7VCC")
		(16 "In7.Cu" signal "L8VCC")
		(18 "In8.Cu" signal "L9GND")
		(20 "In9.Cu" signal "L10")
		(22 "In10.Cu" signal "L11GND")
		(24 "In11.Cu" signal "L12")
		(26 "In12.Cu" signal "L13GND")
		(2 "B.Cu" signal "BOTTOM")
		(9 "F.Adhes" user "F.Adhesive")
		(11 "B.Adhes" user "B.Adhesive")
		(13 "F.Paste" user "Package Geometry/Pastemask Top")
		(15 "B.Paste" user "Package Geometry/Pastemask Bottom")
		(5 "F.SilkS" user "Ref Des/Silkscreen Top")
		(7 "B.SilkS" user "Ref Des/Silkscreen Bottom")
		(1 "F.Mask" user "Board Geometry/Soldermask Top")
		(3 "B.Mask" user "Board Geometry/Soldermask Bottom")
		(17 "Dwgs.User" user "User.Drawings")
		(19 "Cmts.User" user "User.Comments")
		(21 "Eco1.User" user "User.Eco1")
		(23 "Eco2.User" user "User.Eco2")
		(25 "Edge.Cuts" user "Board Geometry/Outline")
		(27 "Margin" user)
		(31 "F.CrtYd" user "Package Geometry/Place Bound Top")
		(29 "B.CrtYd" user "Package Geometry/Place Bound Bottom")
		(35 "F.Fab" user "Ref Des/Assembly Top")
		(33 "B.Fab" user "Ref Des/Assembly Bottom")
	)
	(footprint ""
		(layer "B.Cu")
		(at 402.209 -33.655)
		(property "Reference" "C25W36"
			(at -0.97536 0.76708 90)
			(unlocked yes)
			(layer "B.SilkS")
			(effects
				(font
					(size 0.4064 0.254)
					(thickness 0.1524)
				)
				(justify mirror)
			)
		)
		(property "Value" ""
			(at 0 0 0)
			(layer "B.Fab")
			(effects
				(font
					(size 1.27 1.27)
				)
				(justify mirror)
			)
		)
		(duplicate_pad_numbers_are_jumpers no)
		(fp_poly
			(pts
				(xy 0.4953 -0.2032) (xy -0.4953 -0.2032) (xy -0.4953 1.6002) (xy 0.4953 1.6002)
			)
			(stroke
				(width 0)
				(type default)
			)
			(fill no)
			(layer "B.CrtYd")
		)
		(fp_line
			(start -0.4953 -0.2032)
			(end -0.4953 1.6002)
			(stroke
				(width 0.1)
				(type default)
			)
			(layer "B.Fab")
		)
		(fp_line
			(start -0.4953 1.6002)
			(end 0.4953 1.6002)
			(stroke
				(width 0.1)
				(type default)
			)
			(layer "B.Fab")
		)
		(fp_line
			(start 0.4953 -0.2032)
			(end -0.4953 -0.2032)
			(stroke
				(width 0.1)
				(type default)
			)
			(layer "B.Fab")
		)
		(fp_line
			(start 0.4953 1.6002)
			(end 0.4953 -0.2032)
			(stroke
				(width 0.1)
				(type default)
			)
			(layer "B.Fab")
		)
		(pad "1" smd rect
			(at 0 0 180)
			(size 0.762 0.889)
			(layers "B.Cu" "B.Mask" "B.Paste")
			(net "VCC_DACAV3V3")
		)
		(pad "2" smd rect
			(at 0 1.397 180)
			(size 0.762 0.889)
			(layers "B.Cu" "B.Mask" "B.Paste")
			(net "GND")
		)
		(zone
			(layer "B.Cu")
			(hatch none 0.5)
			(connect_pads
				(clearance 0)
			)
			(min_thickness 0.25)
			(keepout
				(tracks not_allowed)
				(vias allowed)
				(pads allowed)
				(copperpour not_allowed)
				(footprints allowed)
			)
			(placement
				(enabled no)
				(sheetname "")
			)
			(fill
				(thermal_gap 0.5)
				(thermal_bridge_width 0.5)
				(island_removal_mode 0)
			)
			(polygon
				(pts
					(xy 402.59 -33.2105) (xy 401.828 -33.2105) (xy 401.828 -32.7025) (xy 402.59 -32.7025)
				)
			)
		)
	)
	(footprint ""
		(layer "B.Cu")
		(at 346.456 -104.267 180)
		(property "Reference" "C22W29"
			(at 0 0 0)
			(layer "B.SilkS")
			(hide yes)
			(effects
				(font
					(size 1.27 1.27)
				)
				(justify mirror)
			)
		)
		(property "Value" "*"
			(at 0.0762 -6.2357 180)
			(unlocked yes)
			(layer "B.Fab")
			(hide yes)
			(effects
				(font
					(size 1.27 1.016)
					(thickness 0.1524)
				)
				(justify mirror)
			)
		)
		(property "Device Type" "SC22U16V5MX-4-GP_SMD-BCG5-SC22A"
			(at 0.0762 -8.2677 180)
			(unlocked yes)
			(layer "B.Fab")
			(hide yes)
			(effects
				(font
					(size 1.27 1.016)
					(thickness 0.1524)
				)
				(justify mirror)
			)
		)
		(duplicate_pad_numbers_are_jumpers no)
		(fp_line
			(start -0.635 0)
			(end 0.635 0)
			(stroke
				(width 0.508)
				(type default)
			)
			(layer "B.SilkS")
		)
		(fp_rect
			(start 0.9652 1.778)
			(end -0.9652 -1.778)
			(stroke
				(width 0)
				(type default)
			)
			(fill no)
			(layer "B.CrtYd")
		)
		(fp_poly
			(pts
				(xy 0.9652 -1.778) (xy -0.9652 -1.778) (xy -0.9652 1.778) (xy 0.9652 1.778)
			)
			(stroke
				(width 0)
				(type default)
			)
			(fill no)
			(layer "B.Fab")
		)
		(pad "1" smd rect
			(at 0 -0.9652)
			(size 1.397 1.143)
			(layers "B.Cu" "B.Mask" "B.Paste")
			(net "VR_FET_SW_P12V_STBY_PVCCIO_CPU0")
		)
		(pad "2" smd rect
			(at 0 0.9652)
			(size 1.397 1.143)
			(layers "B.Cu" "B.Mask" "B.Paste")
			(net "GND")
		)
	)
	(footprint ""
		(layer "B.Cu")
		(at 399.4404 -74.168 90)
		(property "Reference" "C6W2"
			(at 0.8382 -0.67818 90)
			(unlocked yes)
			(layer "B.SilkS")
			(effects
				(font
					(size 0.4064 0.254)
					(thickness 0.1524)
				)
				(justify left mirror)
			)
		)
		(property "Value" ""
			(at 0 0 90)
			(layer "B.Fab")
			(effects
				(font
					(size 1.27 1.27)
				)
				(justify mirror)
			)
		)
		(duplicate_pad_numbers_are_jumpers no)
		(fp_poly
			(pts
				(xy -0.3048 -0.1016) (xy -0.3048 0.9906) (xy 0.3048 0.9906) (xy 0.3048 -0.1016)
			)
			(stroke
				(width 0)
				(type default)
			)
			(fill no)
			(layer "B.CrtYd")
		)
		(fp_line
			(start 0.3048 -0.1016)
			(end 0.3048 0.9906)
			(stroke
				(width 0.1)
				(type default)
			)
			(layer "B.Fab")
		)
		(fp_line
			(start -0.3048 -0.1016)
			(end 0.3048 -0.1016)
			(stroke
				(width 0.1)
				(type default)
			)
			(layer "B.Fab")
		)
		(fp_line
			(start 0.3048 0.9906)
			(end -0.3048 0.9906)
			(stroke
				(width 0.1)
				(type default)
			)
			(layer "B.Fab")
		)
		(fp_line
			(start -0.3048 0.9906)
			(end -0.3048 -0.1016)
			(stroke
				(width 0.1)
				(type default)
			)
			(layer "B.Fab")
		)
		(pad "1" smd rect
			(at 0 0 270)
			(size 0.508 0.508)
			(layers "B.Cu" "B.Mask" "B.Paste")
			(net "P3V3_STBY")
		)
		(pad "2" smd rect
			(at 0 0.889 270)
			(size 0.508 0.508)
			(layers "B.Cu" "B.Mask" "B.Paste")
			(net "GND")
		)
		(zone
			(layer "B.Cu")
			(hatch none 0.5)
			(connect_pads
				(clearance 0)
			)
			(min_thickness 0.25)
			(keepout
				(tracks allowed)
				(vias not_allowed)
				(pads allowed)
				(copperpour not_allowed)
				(footprints allowed)
			)
			(placement
				(enabled no)
				(sheetname "")
			)
			(fill
				(thermal_gap 0.5)
				(thermal_bridge_width 0.5)
				(island_removal_mode 0)
			)
			(polygon
				(pts
					(xy 399.6944 -74.422) (xy 399.6944 -73.914) (xy 400.0754 -73.914) (xy 400.0754 -74.422)
				)
			)
		)
		(zone
			(layer "B.Cu")
			(hatch none 0.5)
			(connect_pads
				(clearance 0)
			)
			(min_thickness 0.25)
			(keepout
				(tracks not_allowed)
				(vias allowed)
				(pads allowed)
				(copperpour not_allowed)
				(footprints allowed)
			)
			(placement
				(enabled no)
				(sheetname "")
			)
			(fill
				(thermal_gap 0.5)
				(thermal_bridge_width 0.5)
				(island_removal_mode 0)
			)
			(polygon
				(pts
					(xy 400.0754 -74.422) (xy 400.0754 -73.914) (xy 399.6944 -73.914) (xy 399.6944 -74.422)
				)
			)
		)
	)
	(footprint ""
		(layer "B.Cu")
		(at 178.562 -51.562 -90)
		(property "Reference" "C6R14"
			(at 0 0 90)
			(layer "B.SilkS")
			(hide yes)
			(effects
				(font
					(size 1.27 1.27)
				)
				(justify mirror)
			)
		)
		(property "Value" ""
			(at 0 0 90)
			(layer "B.Fab")
			(effects
				(font
					(size 1.27 1.27)
				)
				(justify mirror)
			)
		)
		(duplicate_pad_numbers_are_jumpers no)
		(fp_poly
			(pts
				(xy 0.7239 -0.2159) (xy -0.7239 -0.2159) (xy -0.7239 1.9939) (xy 0.7239 1.9939)
			)
			(stroke
				(width 0)
				(type default)
			)
			(fill no)
			(layer "B.CrtYd")
		)
		(fp_line
			(start -0.7239 1.9939)
			(end -0.7239 -0.2159)
			(stroke
				(width 0.1)
				(type default)
			)
			(layer "B.Fab")
		)
		(fp_line
			(start 0.7239 1.9939)
			(end -0.7239 1.9939)
			(stroke
				(width 0.1)
				(type default)
			)
			(layer "B.Fab")
		)
		(fp_line
			(start -0.7239 -0.2159)
			(end 0.7239 -0.2159)
			(stroke
				(width 0.1)
				(type default)
			)
			(layer "B.Fab")
		)
		(fp_line
			(start 0.7239 -0.2159)
			(end 0.7239 1.9939)
			(stroke
				(width 0.1)
				(type default)
			)
			(layer "B.Fab")
		)
		(pad "1" smd rect
			(at 0 0 90)
			(size 1.27 1.016)
			(layers "B.Cu" "B.Mask" "B.Paste")
			(net "VR_FET_SW_P12V_STBY_PVCCIN_CPU0")
		)
		(pad "2" smd rect
			(at 0 1.778 90)
			(size 1.27 1.016)
			(layers "B.Cu" "B.Mask" "B.Paste")
			(net "GND")
		)
		(zone
			(layer "B.Cu")
			(hatch none 0.5)
			(connect_pads
				(clearance 0)
			)
			(min_thickness 0.25)
			(keepout
				(tracks not_allowed)
				(vias allowed)
				(pads allowed)
				(copperpour not_allowed)
				(footprints allowed)
			)
			(placement
				(enabled no)
				(sheetname "")
			)
			(fill
				(thermal_gap 0.5)
				(thermal_bridge_width 0.5)
				(island_removal_mode 0)
			)
			(polygon
				(pts
					(xy 178.054 -50.927) (xy 178.054 -52.197) (xy 177.292 -52.197) (xy 177.292 -50.927)
				)
			)
		)
	)
	(footprint ""
		(layer "B.Cu")
		(at 437.769 -20.193 -90)
		(property "Reference" "Q9W3"
			(at 0.229362 -1.59512 270)
			(unlocked yes)
			(layer "B.SilkS")
			(effects
				(font
					(size 1.27 0.9652)
					(thickness 0.1524)
				)
				(justify left mirror)
			)
		)
		(property "Value" ""
			(at 0 0 90)
			(layer "B.Fab")
			(effects
				(font
					(size 1.27 1.27)
				)
				(justify mirror)
			)
		)
		(duplicate_pad_numbers_are_jumpers no)
		(fp_line
			(start -1.778 2.4765)
			(end -1.778 1.5875)
			(stroke
				(width 0.1524)
				(type default)
			)
			(layer "B.SilkS")
		)
		(fp_line
			(start -0.9525 2.4765)
			(end -1.778 2.4765)
			(stroke
				(width 0.1524)
				(type default)
			)
			(layer "B.SilkS")
		)
		(fp_line
			(start -0.381 0.635)
			(end -0.381 1.27)
			(stroke
				(width 0.1524)
				(type default)
			)
			(layer "B.SilkS")
		)
		(fp_line
			(start -1.778 -0.5715)
			(end -1.778 0.3175)
			(stroke
				(width 0.1524)
				(type default)
			)
			(layer "B.SilkS")
		)
		(fp_line
			(start -0.9525 -0.5715)
			(end -1.778 -0.5715)
			(stroke
				(width 0.1524)
				(type default)
			)
			(layer "B.SilkS")
		)
		(fp_circle
			(center 0.9525 -0.9271)
			(end 0.9525 -1.0541)
			(stroke
				(width 0.254)
				(type default)
			)
			(fill no)
			(layer "B.SilkS")
		)
		(fp_poly
			(pts
				(xy -1.778 2.4765) (xy -0.381 2.4765) (xy -0.381 -0.5715) (xy -1.778 -0.5715)
			)
			(stroke
				(width 0)
				(type default)
			)
			(fill no)
			(layer "B.CrtYd")
		)
		(fp_line
			(start -1.778 2.4765)
			(end -1.778 -0.5715)
			(stroke
				(width 0.1)
				(type default)
			)
			(layer "B.Fab")
		)
		(fp_line
			(start -0.381 2.4765)
			(end -1.778 2.4765)
			(stroke
				(width 0.1)
				(type default)
			)
			(layer "B.Fab")
		)
		(fp_line
			(start -1.778 -0.5715)
			(end -0.381 -0.5715)
			(stroke
				(width 0.1)
				(type default)
			)
			(layer "B.Fab")
		)
		(fp_line
			(start -0.381 -0.5715)
			(end -0.381 2.4765)
			(stroke
				(width 0.1)
				(type default)
			)
			(layer "B.Fab")
		)
		(fp_circle
			(center 0.9525 -0.9271)
			(end 0.9525 -1.0541)
			(stroke
				(width 0.254)
				(type default)
			)
			(fill no)
			(layer "B.Fab")
		)
		(pad "1" smd rect
			(at 0 0 90)
			(size 1.143 0.508)
			(layers "B.Cu" "B.Mask" "B.Paste")
			(net "FM_TPM_PRES_RST")
		)
		(pad "2" smd rect
			(at 0 1.905 90)
			(size 1.143 0.508)
			(layers "B.Cu" "B.Mask" "B.Paste")
			(net "GND")
		)
		(pad "3" smd rect
			(at -2.159 0.9525 90)
			(size 1.143 0.508)
			(layers "B.Cu" "B.Mask" "B.Paste")
			(net "RST_BMC_EXTRST_N")
		)
	)
	(footprint ""
		(layer "B.Cu")
		(at 259.9182 -126.1364 -90)
		(property "Reference" "C5M13"
			(at 0 0 90)
			(layer "B.SilkS")
			(hide yes)
			(effects
				(font
					(size 1.27 1.27)
				)
				(justify mirror)
			)
		)
		(property "Value" ""
			(at 0 0 90)
			(layer "B.Fab")
			(effects
				(font
					(size 1.27 1.27)
				)
				(justify mirror)
			)
		)
		(duplicate_pad_numbers_are_jumpers no)
		(fp_rect
			(start 0.500126 1.598422)
			(end -0.500126 -0.201422)
			(stroke
				(width 0)
				(type default)
			)
			(fill no)
			(layer "B.CrtYd")
		)
		(fp_line
			(start -0.500126 1.598422)
			(end 0.500126 1.598422)
			(stroke
				(width 0.1)
				(type default)
			)
			(layer "B.Fab")
		)
		(fp_line
			(start 0.500126 1.598422)
			(end 0.500126 -0.201422)
			(stroke
				(width 0.1)
				(type default)
			)
			(layer "B.Fab")
		)
		(fp_line
			(start -0.500126 -0.201422)
			(end -0.500126 1.598422)
			(stroke
				(width 0.1)
				(type default)
			)
			(layer "B.Fab")
		)
		(fp_line
			(start 0.500126 -0.201422)
			(end -0.500126 -0.201422)
			(stroke
				(width 0.1)
				(type default)
			)
			(layer "B.Fab")
		)
		(pad "1" smd rect
			(at 0 0 180)
			(size 0.889 0.9906)
			(layers "B.Cu" "B.Mask" "B.Paste")
			(net "PVTT_DEF")
		)
		(pad "2" smd rect
			(at 0 1.397 180)
			(size 0.889 0.9906)
			(layers "B.Cu" "B.Mask" "B.Paste")
			(net "GND")
		)
		(zone
			(layer "B.Cu")
			(hatch none 0.5)
			(connect_pads
				(clearance 0)
			)
			(min_thickness 0.25)
			(keepout
				(tracks allowed)
				(vias not_allowed)
				(pads allowed)
				(copperpour not_allowed)
				(footprints allowed)
			)
			(placement
				(enabled no)
				(sheetname "")
			)
			(fill
				(thermal_gap 0.5)
				(thermal_bridge_width 0.5)
				(island_removal_mode 0)
			)
			(polygon
				(pts
					(xy 258.9657 -125.6411) (xy 259.4737 -125.6411) (xy 259.4737 -126.6317) (xy 258.9657 -126.6317)
				)
			)
		)
		(zone
			(layer "B.Cu")
			(hatch none 0.5)
			(connect_pads
				(clearance 0)
			)
			(min_thickness 0.25)
			(keepout
				(tracks not_allowed)
				(vias allowed)
				(pads allowed)
				(copperpour not_allowed)
				(footprints allowed)
			)
			(placement
				(enabled no)
				(sheetname "")
			)
			(fill
				(thermal_gap 0.5)
				(thermal_bridge_width 0.5)
				(island_removal_mode 0)
			)
			(polygon
				(pts
					(xy 258.9657 -125.6411) (xy 259.4737 -125.6411) (xy 259.4737 -126.6317) (xy 258.9657 -126.6317)
				)
			)
		)
	)
	(footprint ""
		(layer "B.Cu")
		(at 413.0675 -25.273 -90)
		(property "Reference" "C25W33"
			(at 0.8382 -0.67818 270)
			(unlocked yes)
			(layer "B.SilkS")
			(effects
				(font
					(size 0.4064 0.254)
					(thickness 0.1524)
				)
				(justify left mirror)
			)
		)
		(property "Value" ""
			(at 0 0 90)
			(layer "B.Fab")
			(effects
				(font
					(size 1.27 1.27)
				)
				(justify mirror)
			)
		)
		(duplicate_pad_numbers_are_jumpers no)
		(fp_poly
			(pts
				(xy -0.3048 -0.1016) (xy -0.3048 0.9906) (xy 0.3048 0.9906) (xy 0.3048 -0.1016)
			)
			(stroke
				(width 0)
				(type default)
			)
			(fill no)
			(layer "B.CrtYd")
		)
		(fp_line
			(start -0.3048 0.9906)
			(end -0.3048 -0.1016)
			(stroke
				(width 0.1)
				(type default)
			)
			(layer "B.Fab")
		)
		(fp_line
			(start 0.3048 0.9906)
			(end -0.3048 0.9906)
			(stroke
				(width 0.1)
				(type default)
			)
			(layer "B.Fab")
		)
		(fp_line
			(start -0.3048 -0.1016)
			(end 0.3048 -0.1016)
			(stroke
				(width 0.1)
				(type default)
			)
			(layer "B.Fab")
		)
		(fp_line
			(start 0.3048 -0.1016)
			(end 0.3048 0.9906)
			(stroke
				(width 0.1)
				(type default)
			)
			(layer "B.Fab")
		)
		(pad "1" smd rect
			(at 0 0 90)
			(size 0.508 0.508)
			(layers "B.Cu" "B.Mask" "B.Paste")
			(net "VCC_ADCAV3V3")
		)
		(pad "2" smd rect
			(at 0 0.889 90)
			(size 0.508 0.508)
			(layers "B.Cu" "B.Mask" "B.Paste")
			(net "GND")
		)
		(zone
			(layer "B.Cu")
			(hatch none 0.5)
			(connect_pads
				(clearance 0)
			)
			(min_thickness 0.25)
			(keepout
				(tracks not_allowed)
				(vias allowed)
				(pads allowed)
				(copperpour not_allowed)
				(footprints allowed)
			)
			(placement
				(enabled no)
				(sheetname "")
			)
			(fill
				(thermal_gap 0.5)
				(thermal_bridge_width 0.5)
				(island_removal_mode 0)
			)
			(polygon
				(pts
					(xy 412.4325 -25.019) (xy 412.4325 -25.527) (xy 412.8135 -25.527) (xy 412.8135 -25.019)
				)
			)
		)
		(zone
			(layer "B.Cu")
			(hatch none 0.5)
			(connect_pads
				(clearance 0)
			)
			(min_thickness 0.25)
			(keepout
				(tracks allowed)
				(vias not_allowed)
				(pads allowed)
				(copperpour not_allowed)
				(footprints allowed)
			)
			(placement
				(enabled no)
				(sheetname "")
			)
			(fill
				(thermal_gap 0.5)
				(thermal_bridge_width 0.5)
				(island_removal_mode 0)
			)
			(polygon
				(pts
					(xy 412.8135 -25.019) (xy 412.8135 -25.527) (xy 412.4325 -25.527) (xy 412.4325 -25.019)
				)
			)
		)
	)
	(footprint ""
		(layer "B.Cu")
		(at 22.0345 -83.312 -90)
		(property "Reference" "U9P1"
			(at -1.05918 -0.62357 270)
			(unlocked yes)
			(layer "B.SilkS")
			(effects
				(font
					(size 0.7874 0.5842)
					(thickness 0.1524)
				)
				(justify mirror)
			)
		)
		(property "Value" ""
			(at 0 0 90)
			(layer "B.Fab")
			(effects
				(font
					(size 1.27 1.27)
				)
				(justify mirror)
			)
		)
		(duplicate_pad_numbers_are_jumpers no)
		(fp_circle
			(center 1.0795 -0.054102)
			(end 1.0795 -0.181102)
			(stroke
				(width 0.254)
				(type default)
			)
			(fill no)
			(layer "B.SilkS")
		)
		(fp_rect
			(start 0.216154 1.27508)
			(end -1.333754 -0.275082)
			(stroke
				(width 0)
				(type default)
			)
			(fill no)
			(layer "B.CrtYd")
		)
		(fp_line
			(start -1.333754 1.27508)
			(end 0.216154 1.27508)
			(stroke
				(width 0.1)
				(type default)
			)
			(layer "B.Fab")
		)
		(fp_line
			(start 0.216154 1.27508)
			(end 0.216154 -0.275082)
			(stroke
				(width 0.1)
				(type default)
			)
			(layer "B.Fab")
		)
		(fp_line
			(start -1.333754 -0.275082)
			(end -1.333754 1.27508)
			(stroke
				(width 0.1)
				(type default)
			)
			(layer "B.Fab")
		)
		(fp_line
			(start 0.216154 -0.275082)
			(end -1.333754 -0.275082)
			(stroke
				(width 0.1)
				(type default)
			)
			(layer "B.Fab")
		)
		(fp_circle
			(center 1.0795 -0.054102)
			(end 1.0795 -0.181102)
			(stroke
				(width 0.254)
				(type default)
			)
			(fill no)
			(layer "B.Fab")
		)
		(pad "1" smd rect
			(at 0 0 90)
			(size 0.9398 0.3048)
			(layers "B.Cu" "B.Mask" "B.Paste")
			(net "A_P12V_STBY_FPH_GATE")
		)
		(pad "2" smd rect
			(at 0.0254 0.500126 90)
			(size 0.889 0.3048)
			(layers "B.Cu" "B.Mask" "B.Paste")
			(net "P12V_STBY")
		)
		(pad "3" smd rect
			(at 0.0254 0.999998 90)
			(size 0.889 0.3048)
			(layers "B.Cu" "B.Mask" "B.Paste")
			(net "A_P12V_STBY_FP_TRIGGER")
		)
		(pad "4" smd rect
			(at -1.143 0.999998 90)
			(size 0.889 0.3048)
			(layers "B.Cu" "B.Mask" "B.Paste")
			(net "A_P12V_STBY_ADR_TRIGGER")
		)
		(pad "5" smd rect
			(at -1.143 0.500126 90)
			(size 0.889 0.3048)
			(layers "B.Cu" "B.Mask" "B.Paste")
			(net "GND")
		)
		(pad "6" smd rect
			(at -1.143 0 90)
			(size 0.889 0.3048)
			(layers "B.Cu" "B.Mask" "B.Paste")
			(net "FM_UV_ADR_TRIGGER_N")
		)
	)
)
